# T6G (Grand Teton) — schematic netlist excerpt (pin names and nets, part order shuffled) for the footprints in the layout excerpt that follows; sources: Cadence DE-HDL packaged netlist, KiCad conversion of 04192023_DAF0TMB3IC0_F0TG_MB_C_brd_V02_OCP.brd

R229  Q_RES  33 5% CHIP  pkg 0402LF  page 81 : A = PVDDIO_P0_EN ; B = FM_PVDDIO_P0_EN
C2346  Q_CAP  22UF 4V 20% X6S  pkg C0402  page 73 : A = PVDDCR_CPU0_P1 ; B = GND
C1071  Q_CAP  0.1UF 10V 10% X7S  pkg C0201  page 186 : A = P3V3_AUX ; B = GND

(kicad_pcb
	(version 20260206)
	(generator "pcbnew")
	(generator_version "10.0")
	(general
		(thickness 1.6)
		(legacy_teardrops no)
	)
	(paper "A4")
	(title_block
		(title "04192023_DAF0TMB3IC0_F0TG_MB_C_brd_V02_OCP.brd")
		(comment 1 "Grand Teton / footprints 5950-5952 of 8354")
	)
	(layers
		(0 "F.Cu" signal "TOP")
		(4 "In1.Cu" signal "GND")
		(6 "In2.Cu" signal "IN1")
		(8 "In3.Cu" signal "GND1")
		(10 "In4.Cu" signal "IN2")
		(12 "In5.Cu" signal "GND2")
		(14 "In6.Cu" signal "IN3")
		(16 "In7.Cu" signal "GND3")
		(18 "In8.Cu" signal "VCC")
		(20 "In9.Cu" signal "VCC1")
		(22 "In10.Cu" signal "GND4")
		(24 "In11.Cu" signal "IN4")
		(26 "In12.Cu" signal "GND5")
		(28 "In13.Cu" signal "IN5")
		(30 "In14.Cu" signal "GND6")
		(32 "In15.Cu" signal "IN6")
		(34 "In16.Cu" signal "GND7")
		(2 "B.Cu" signal "BOTTOM")
		(9 "F.Adhes" user "F.Adhesive")
		(11 "B.Adhes" user "B.Adhesive")
		(13 "F.Paste" user "Package Geometry/Pastemask Top")
		(15 "B.Paste" user "Package Geometry/Pastemask Bottom")
		(5 "F.SilkS" user "Ref Des/Silkscreen Top")
		(7 "B.SilkS" user "Ref Des/Silkscreen Bottom")
		(1 "F.Mask" user "Board Geometry/Soldermask Top")
		(3 "B.Mask" user "Board Geometry/Soldermask Bottom")
		(17 "Dwgs.User" user "User.Drawings")
		(19 "Cmts.User" user "User.Comments")
		(21 "Eco1.User" user "User.Eco1")
		(23 "Eco2.User" user "User.Eco2")
		(25 "Edge.Cuts" user "Board Geometry/Outline")
		(27 "Margin" user)
		(31 "F.CrtYd" user "Package Geometry/Place Bound Top")
		(29 "B.CrtYd" user "Package Geometry/Place Bound Bottom")
		(35 "F.Fab" user "Ref Des/Assembly Top")
		(33 "B.Fab" user "Ref Des/Assembly Bottom")
	)
	(footprint ""
		(layer "B.Cu")
		(at 197.523608 -105.497376)
		(property "Reference" "R229"
			(at 0 0 0)
			(layer "B.SilkS")
			(hide yes)
			(effects
				(font
					(size 1.27 1.27)
				)
				(justify mirror)
			)
		)
		(property "Value" ""
			(at 0 0 0)
			(layer "B.Fab")
			(effects
				(font
					(size 1.27 1.27)
				)
				(justify mirror)
			)
		)
		(duplicate_pad_numbers_are_jumpers no)
		(fp_line
			(start -0.7874 -0.4064)
			(end -0.7874 0.4064)
			(stroke
				(width 0.1524)
				(type default)
			)
			(layer "B.SilkS")
		)
		(fp_line
			(start -0.7874 0.4064)
			(end 0.7874 0.4064)
			(stroke
				(width 0.1524)
				(type default)
			)
			(layer "B.SilkS")
		)
		(fp_line
			(start 0.7874 -0.4064)
			(end -0.7874 -0.4064)
			(stroke
				(width 0.1524)
				(type default)
			)
			(layer "B.SilkS")
		)
		(fp_line
			(start 0.7874 0.4064)
			(end 0.7874 -0.4064)
			(stroke
				(width 0.1524)
				(type default)
			)
			(layer "B.SilkS")
		)
		(fp_line
			(start -0.67945 -0.3048)
			(end -0.67945 0.3048)
			(stroke
				(width 0.1)
				(type default)
			)
			(layer "B.Fab")
		)
		(fp_line
			(start -0.67945 0.3048)
			(end -0.120396 0.3048)
			(stroke
				(width 0.1)
				(type default)
			)
			(layer "B.Fab")
		)
		(fp_line
			(start -0.12065 -0.3048)
			(end -0.67945 -0.3048)
			(stroke
				(width 0.1)
				(type default)
			)
			(layer "B.Fab")
		)
		(fp_line
			(start -0.12065 -0.2794)
			(end -0.12065 -0.3048)
			(stroke
				(width 0.1)
				(type default)
			)
			(layer "B.Fab")
		)
		(fp_line
			(start -0.120396 0.2794)
			(end 0.12065 0.2794)
			(stroke
				(width 0.1)
				(type default)
			)
			(layer "B.Fab")
		)
		(fp_line
			(start -0.120396 0.3048)
			(end -0.120396 0.2794)
			(stroke
				(width 0.1)
				(type default)
			)
			(layer "B.Fab")
		)
		(fp_line
			(start 0.12065 -0.305054)
			(end 0.12065 -0.2794)
			(stroke
				(width 0.1)
				(type default)
			)
			(layer "B.Fab")
		)
		(fp_line
			(start 0.12065 -0.2794)
			(end -0.12065 -0.2794)
			(stroke
				(width 0.1)
				(type default)
			)
			(layer "B.Fab")
		)
		(fp_line
			(start 0.12065 0.2794)
			(end 0.12065 0.3048)
			(stroke
				(width 0.1)
				(type default)
			)
			(layer "B.Fab")
		)
		(fp_line
			(start 0.12065 0.3048)
			(end 0.67945 0.3048)
			(stroke
				(width 0.1)
				(type default)
			)
			(layer "B.Fab")
		)
		(fp_line
			(start 0.67945 -0.305054)
			(end 0.12065 -0.305054)
			(stroke
				(width 0.1)
				(type default)
			)
			(layer "B.Fab")
		)
		(fp_line
			(start 0.67945 0.3048)
			(end 0.67945 -0.305054)
			(stroke
				(width 0.1)
				(type default)
			)
			(layer "B.Fab")
		)
		(pad "1" smd circle
			(at 0.40005 0 180)
			(size 0 0)
			(layers "B.Cu" "B.Mask" "B.Paste")
			(net "PVDDIO_P0_EN")
		)
		(pad "2" smd circle
			(at -0.40005 0 180)
			(size 0 0)
			(layers "B.Cu" "B.Mask" "B.Paste")
			(net "FM_PVDDIO_P0_EN")
		)
	)
	(footprint ""
		(layer "B.Cu")
		(at 101.414834 -245.487952 180)
		(property "Reference" "C2346"
			(at 0 0 0)
			(layer "B.SilkS")
			(hide yes)
			(effects
				(font
					(size 1.27 1.27)
				)
				(justify mirror)
			)
		)
		(property "Value" ""
			(at 0 0 0)
			(layer "B.Fab")
			(effects
				(font
					(size 1.27 1.27)
				)
				(justify mirror)
			)
		)
		(duplicate_pad_numbers_are_jumpers no)
		(fp_line
			(start 0.7874 0.4064)
			(end 0.7874 -0.4064)
			(stroke
				(width 0.1524)
				(type default)
			)
			(layer "B.SilkS")
		)
		(fp_line
			(start 0.7874 -0.4064)
			(end -0.7874 -0.4064)
			(stroke
				(width 0.1524)
				(type default)
			)
			(layer "B.SilkS")
		)
		(fp_line
			(start -0.7874 0.4064)
			(end 0.7874 0.4064)
			(stroke
				(width 0.1524)
				(type default)
			)
			(layer "B.SilkS")
		)
		(fp_line
			(start -0.7874 -0.4064)
			(end -0.7874 0.4064)
			(stroke
				(width 0.1524)
				(type default)
			)
			(layer "B.SilkS")
		)
		(fp_line
			(start 0.67945 0.3048)
			(end 0.67945 -0.305054)
			(stroke
				(width 0.1)
				(type default)
			)
			(layer "B.Fab")
		)
		(fp_line
			(start 0.67945 -0.305054)
			(end 0.12065 -0.305054)
			(stroke
				(width 0.1)
				(type default)
			)
			(layer "B.Fab")
		)
		(fp_line
			(start 0.12065 0.3048)
			(end 0.67945 0.3048)
			(stroke
				(width 0.1)
				(type default)
			)
			(layer "B.Fab")
		)
		(fp_line
			(start 0.12065 0.2794)
			(end 0.12065 0.3048)
			(stroke
				(width 0.1)
				(type default)
			)
			(layer "B.Fab")
		)
		(fp_line
			(start 0.12065 -0.2794)
			(end -0.12065 -0.2794)
			(stroke
				(width 0.1)
				(type default)
			)
			(layer "B.Fab")
		)
		(fp_line
			(start 0.12065 -0.305054)
			(end 0.12065 -0.2794)
			(stroke
				(width 0.1)
				(type default)
			)
			(layer "B.Fab")
		)
		(fp_line
			(start -0.120396 0.3048)
			(end -0.120396 0.2794)
			(stroke
				(width 0.1)
				(type default)
			)
			(layer "B.Fab")
		)
		(fp_line
			(start -0.120396 0.2794)
			(end 0.12065 0.2794)
			(stroke
				(width 0.1)
				(type default)
			)
			(layer "B.Fab")
		)
		(fp_line
			(start -0.12065 -0.2794)
			(end -0.12065 -0.3048)
			(stroke
				(width 0.1)
				(type default)
			)
			(layer "B.Fab")
		)
		(fp_line
			(start -0.12065 -0.3048)
			(end -0.67945 -0.3048)
			(stroke
				(width 0.1)
				(type default)
			)
			(layer "B.Fab")
		)
		(fp_line
			(start -0.67945 0.3048)
			(end -0.120396 0.3048)
			(stroke
				(width 0.1)
				(type default)
			)
			(layer "B.Fab")
		)
		(fp_line
			(start -0.67945 -0.3048)
			(end -0.67945 0.3048)
			(stroke
				(width 0.1)
				(type default)
			)
			(layer "B.Fab")
		)
		(pad "1" smd circle
			(at 0.40005 0)
			(size 0 0)
			(layers "B.Cu" "B.Mask" "B.Paste")
			(net "PVDDCR_CPU0_P1")
		)
		(pad "2" smd circle
			(at -0.40005 0)
			(size 0 0)
			(layers "B.Cu" "B.Mask" "B.Paste")
			(net "GND")
		)
	)
	(footprint ""
		(layer "B.Cu")
		(at 422.19245 -428.757334 180)
		(property "Reference" "C1071"
			(at 0 0 0)
			(layer "B.SilkS")
			(hide yes)
			(effects
				(font
					(size 1.27 1.27)
				)
				(justify mirror)
			)
		)
		(property "Value" ""
			(at 0 0 0)
			(layer "B.Fab")
			(effects
				(font
					(size 1.27 1.27)
				)
				(justify mirror)
			)
		)
		(duplicate_pad_numbers_are_jumpers no)
		(fp_line
			(start 0.299974 0.150114)
			(end 0.299974 -0.150114)
			(stroke
				(width 0.1)
				(type default)
			)
			(layer "B.Fab")
		)
		(fp_line
			(start 0.299974 -0.150114)
			(end -0.299974 -0.150114)
			(stroke
				(width 0.1)
				(type default)
			)
			(layer "B.Fab")
		)
		(fp_line
			(start -0.299974 0.150114)
			(end 0.299974 0.150114)
			(stroke
				(width 0.1)
				(type default)
			)
			(layer "B.Fab")
		)
		(fp_line
			(start -0.299974 -0.150114)
			(end -0.299974 0.150114)
			(stroke
				(width 0.1)
				(type default)
			)
			(layer "B.Fab")
		)
		(pad "1" smd rect
			(at 0.2667 0)
			(size 0.3048 0.381)
			(layers "B.Cu" "B.Mask" "B.Paste")
			(net "P3V3_AUX")
		)
		(pad "2" smd rect
			(at -0.2667 0)
			(size 0.3048 0.381)
			(layers "B.Cu" "B.Mask" "B.Paste")
			(net "GND")
		)
	)
)
